(kicad_pcb
	(version 20260206)
	(generator "pcbnew")
	(generator_version "10.0")
	(general
		(thickness 1.6)
		(legacy_teardrops no)
	)
	(paper "A4")
	(title_block
		(title "04192023_DAF0TMB3IC0_F0TG_MB_C_brd_V02_OCP.brd")
		(comment 1 "Grand Teton / footprints 3314-3321 of 8354")
	)
	(layers
		(0 "F.Cu" signal "TOP")
		(4 "In1.Cu" signal "GND")
		(6 "In2.Cu" signal "IN1")
		(8 "In3.Cu" signal "GND1")
		(10 "In4.Cu" signal "IN2")
		(12 "In5.Cu" signal "GND2")
		(14 "In6.Cu" signal "IN3")
		(16 "In7.Cu" signal "GND3")
		(18 "In8.Cu" signal "VCC")
		(20 "In9.Cu" signal "VCC1")
		(22 "In10.Cu" signal "GND4")
		(24 "In11.Cu" signal "IN4")
		(26 "In12.Cu" signal "GND5")
		(28 "In13.Cu" signal "IN5")
		(30 "In14.Cu" signal "GND6")
		(32 "In15.Cu" signal "IN6")
		(34 "In16.Cu" signal "GND7")
		(2 "B.Cu" signal "BOTTOM")
		(9 "F.Adhes" user "F.Adhesive")
		(11 "B.Adhes" user "B.Adhesive")
		(13 "F.Paste" user "Package Geometry/Pastemask Top")
		(15 "B.Paste" user "Package Geometry/Pastemask Bottom")
		(5 "F.SilkS" user "Ref Des/Silkscreen Top")
		(7 "B.SilkS" user "Ref Des/Silkscreen Bottom")
		(1 "F.Mask" user "Board Geometry/Soldermask Top")
		(3 "B.Mask" user "Board Geometry/Soldermask Bottom")
		(17 "Dwgs.User" user "User.Drawings")
		(19 "Cmts.User" user "User.Comments")
		(21 "Eco1.User" user "User.Eco1")
		(23 "Eco2.User" user "User.Eco2")
		(25 "Edge.Cuts" user "Board Geometry/Outline")
		(27 "Margin" user)
		(31 "F.CrtYd" user "Package Geometry/Place Bound Top")
		(29 "B.CrtYd" user "Package Geometry/Place Bound Bottom")
		(35 "F.Fab" user "Ref Des/Assembly Top")
		(33 "B.Fab" user "Ref Des/Assembly Bottom")
	)
	(footprint ""
		(layer "F.Cu")
		(at 123.206764 -160.5407 -90)
		(property "Reference" "PR210"
			(at 0 0 270)
			(layer "F.SilkS")
			(hide yes)
			(effects
				(font
					(size 1.27 1.27)
				)
			)
		)
		(property "Value" ""
			(at 0 0 270)
			(layer "F.Fab")
			(effects
				(font
					(size 1.27 1.27)
				)
			)
		)
		(duplicate_pad_numbers_are_jumpers no)
		(fp_line
			(start -0.7874 0.4064)
			(end -0.7874 -0.4064)
			(stroke
				(width 0.1524)
				(type default)
			)
			(layer "F.SilkS")
		)
		(fp_line
			(start 0.7874 0.4064)
			(end -0.7874 0.4064)
			(stroke
				(width 0.1524)
				(type default)
			)
			(layer "F.SilkS")
		)
		(fp_line
			(start -0.7874 -0.4064)
			(end 0.7874 -0.4064)
			(stroke
				(width 0.1524)
				(type default)
			)
			(layer "F.SilkS")
		)
		(fp_line
			(start 0.7874 -0.4064)
			(end 0.7874 0.4064)
			(stroke
				(width 0.1524)
				(type default)
			)
			(layer "F.SilkS")
		)
		(fp_line
			(start -0.67945 0.3048)
			(end -0.67945 -0.305054)
			(stroke
				(width 0.1)
				(type default)
			)
			(layer "F.Fab")
		)
		(fp_line
			(start -0.12065 0.3048)
			(end -0.67945 0.3048)
			(stroke
				(width 0.1)
				(type default)
			)
			(layer "F.Fab")
		)
		(fp_line
			(start 0.120396 0.3048)
			(end 0.120396 0.2794)
			(stroke
				(width 0.1)
				(type default)
			)
			(layer "F.Fab")
		)
		(fp_line
			(start 0.67945 0.3048)
			(end 0.120396 0.3048)
			(stroke
				(width 0.1)
				(type default)
			)
			(layer "F.Fab")
		)
		(fp_line
			(start -0.12065 0.2794)
			(end -0.12065 0.3048)
			(stroke
				(width 0.1)
				(type default)
			)
			(layer "F.Fab")
		)
		(fp_line
			(start 0.120396 0.2794)
			(end -0.12065 0.2794)
			(stroke
				(width 0.1)
				(type default)
			)
			(layer "F.Fab")
		)
		(fp_line
			(start -0.12065 -0.2794)
			(end 0.12065 -0.2794)
			(stroke
				(width 0.1)
				(type default)
			)
			(layer "F.Fab")
		)
		(fp_line
			(start 0.12065 -0.2794)
			(end 0.12065 -0.3048)
			(stroke
				(width 0.1)
				(type default)
			)
			(layer "F.Fab")
		)
		(fp_line
			(start 0.12065 -0.3048)
			(end 0.67945 -0.3048)
			(stroke
				(width 0.1)
				(type default)
			)
			(layer "F.Fab")
		)
		(fp_line
			(start 0.67945 -0.3048)
			(end 0.67945 0.3048)
			(stroke
				(width 0.1)
				(type default)
			)
			(layer "F.Fab")
		)
		(fp_line
			(start -0.67945 -0.305054)
			(end -0.12065 -0.305054)
			(stroke
				(width 0.1)
				(type default)
			)
			(layer "F.Fab")
		)
		(fp_line
			(start -0.12065 -0.305054)
			(end -0.12065 -0.2794)
			(stroke
				(width 0.1)
				(type default)
			)
			(layer "F.Fab")
		)
		(pad "1" smd circle
			(at -0.40005 0 270)
			(size 0 0)
			(layers "F.Cu" "F.Mask" "F.Paste")
			(net "SW_PVDDCR_SOC_P1_BOOT2")
		)
		(pad "2" smd circle
			(at 0.40005 0 270)
			(size 0 0)
			(layers "F.Cu" "F.Mask" "F.Paste")
			(net "SW_PVDDCR_SOC_P1_BOOT2_RC")
		)
	)
	(footprint ""
		(layer "F.Cu")
		(at 135.36168 -28.48102 90)
		(property "Reference" "R6197"
			(at 0 0 90)
			(layer "F.SilkS")
			(hide yes)
			(effects
				(font
					(size 1.27 1.27)
				)
			)
		)
		(property "Value" ""
			(at 0 0 90)
			(layer "F.Fab")
			(effects
				(font
					(size 1.27 1.27)
				)
			)
		)
		(duplicate_pad_numbers_are_jumpers no)
		(fp_line
			(start 0.32512 -0.175006)
			(end 0.32512 0.175006)
			(stroke
				(width 0.1)
				(type default)
			)
			(layer "F.Fab")
		)
		(fp_line
			(start -0.32512 -0.175006)
			(end 0.32512 -0.175006)
			(stroke
				(width 0.1)
				(type default)
			)
			(layer "F.Fab")
		)
		(fp_line
			(start 0.32512 0.175006)
			(end -0.32512 0.175006)
			(stroke
				(width 0.1)
				(type default)
			)
			(layer "F.Fab")
		)
		(fp_line
			(start -0.32512 0.175006)
			(end -0.32512 -0.175006)
			(stroke
				(width 0.1)
				(type default)
			)
			(layer "F.Fab")
		)
		(pad "1" smd rect
			(at -0.2667 0 90)
			(size 0.3048 0.381)
			(layers "F.Cu" "F.Mask" "F.Paste")
			(net "USB2_CPU0_P0_HUB2_R_DN")
		)
		(pad "2" smd rect
			(at 0.2667 0 270)
			(size 0.3048 0.381)
			(layers "F.Cu" "F.Mask" "F.Paste")
			(net "USB2_HUB_EXT_DN")
		)
	)
	(footprint ""
		(layer "F.Cu")
		(at 383.771902 -177.88636 -90)
		(property "Reference" "PC544_3"
			(at 0 0 270)
			(layer "F.SilkS")
			(hide yes)
			(effects
				(font
					(size 1.27 1.27)
				)
			)
		)
		(property "Value" ""
			(at 0 0 270)
			(layer "F.Fab")
			(effects
				(font
					(size 1.27 1.27)
				)
			)
		)
		(duplicate_pad_numbers_are_jumpers no)
		(fp_line
			(start -0.7874 0.4064)
			(end -0.7874 -0.4064)
			(stroke
				(width 0.1524)
				(type default)
			)
			(layer "F.SilkS")
		)
		(fp_line
			(start 0.7874 0.4064)
			(end -0.7874 0.4064)
			(stroke
				(width 0.1524)
				(type default)
			)
			(layer "F.SilkS")
		)
		(fp_line
			(start -0.7874 -0.4064)
			(end 0.7874 -0.4064)
			(stroke
				(width 0.1524)
				(type default)
			)
			(layer "F.SilkS")
		)
		(fp_line
			(start 0.7874 -0.4064)
			(end 0.7874 0.4064)
			(stroke
				(width 0.1524)
				(type default)
			)
			(layer "F.SilkS")
		)
		(fp_line
			(start -0.67945 0.3048)
			(end -0.67945 -0.305054)
			(stroke
				(width 0.1)
				(type default)
			)
			(layer "F.Fab")
		)
		(fp_line
			(start -0.12065 0.3048)
			(end -0.67945 0.3048)
			(stroke
				(width 0.1)
				(type default)
			)
			(layer "F.Fab")
		)
		(fp_line
			(start 0.120396 0.3048)
			(end 0.120396 0.2794)
			(stroke
				(width 0.1)
				(type default)
			)
			(layer "F.Fab")
		)
		(fp_line
			(start 0.67945 0.3048)
			(end 0.120396 0.3048)
			(stroke
				(width 0.1)
				(type default)
			)
			(layer "F.Fab")
		)
		(fp_line
			(start -0.12065 0.2794)
			(end -0.12065 0.3048)
			(stroke
				(width 0.1)
				(type default)
			)
			(layer "F.Fab")
		)
		(fp_line
			(start 0.120396 0.2794)
			(end -0.12065 0.2794)
			(stroke
				(width 0.1)
				(type default)
			)
			(layer "F.Fab")
		)
		(fp_line
			(start -0.12065 -0.2794)
			(end 0.12065 -0.2794)
			(stroke
				(width 0.1)
				(type default)
			)
			(layer "F.Fab")
		)
		(fp_line
			(start 0.12065 -0.2794)
			(end 0.12065 -0.3048)
			(stroke
				(width 0.1)
				(type default)
			)
			(layer "F.Fab")
		)
		(fp_line
			(start 0.12065 -0.3048)
			(end 0.67945 -0.3048)
			(stroke
				(width 0.1)
				(type default)
			)
			(layer "F.Fab")
		)
		(fp_line
			(start 0.67945 -0.3048)
			(end 0.67945 0.3048)
			(stroke
				(width 0.1)
				(type default)
			)
			(layer "F.Fab")
		)
		(fp_line
			(start -0.67945 -0.305054)
			(end -0.12065 -0.305054)
			(stroke
				(width 0.1)
				(type default)
			)
			(layer "F.Fab")
		)
		(fp_line
			(start -0.12065 -0.305054)
			(end -0.12065 -0.2794)
			(stroke
				(width 0.1)
				(type default)
			)
			(layer "F.Fab")
		)
		(pad "1" smd circle
			(at -0.40005 0 270)
			(size 0 0)
			(layers "F.Cu" "F.Mask" "F.Paste")
			(net "PVDDCR_CPU0_P0_VCCS")
		)
		(pad "2" smd circle
			(at 0.40005 0 270)
			(size 0 0)
			(layers "F.Cu" "F.Mask" "F.Paste")
			(net "GND")
		)
	)
	(footprint ""
		(layer "F.Cu")
		(at 286.980884 -370.318792 90)
		(property "Reference" "R8047"
			(at 0 0 90)
			(layer "F.SilkS")
			(hide yes)
			(effects
				(font
					(size 1.27 1.27)
				)
			)
		)
		(property "Value" ""
			(at 0 0 90)
			(layer "F.Fab")
			(effects
				(font
					(size 1.27 1.27)
				)
			)
		)
		(duplicate_pad_numbers_are_jumpers no)
		(fp_line
			(start 0.7874 -0.4064)
			(end 0.7874 0.4064)
			(stroke
				(width 0.1524)
				(type default)
			)
			(layer "F.SilkS")
		)
		(fp_line
			(start -0.7874 -0.4064)
			(end 0.7874 -0.4064)
			(stroke
				(width 0.1524)
				(type default)
			)
			(layer "F.SilkS")
		)
		(fp_line
			(start 0.7874 0.4064)
			(end -0.7874 0.4064)
			(stroke
				(width 0.1524)
				(type default)
			)
			(layer "F.SilkS")
		)
		(fp_line
			(start -0.7874 0.4064)
			(end -0.7874 -0.4064)
			(stroke
				(width 0.1524)
				(type default)
			)
			(layer "F.SilkS")
		)
		(fp_line
			(start -0.12065 -0.305054)
			(end -0.12065 -0.2794)
			(stroke
				(width 0.1)
				(type default)
			)
			(layer "F.Fab")
		)
		(fp_line
			(start -0.67945 -0.305054)
			(end -0.12065 -0.305054)
			(stroke
				(width 0.1)
				(type default)
			)
			(layer "F.Fab")
		)
		(fp_line
			(start 0.67945 -0.3048)
			(end 0.67945 0.3048)
			(stroke
				(width 0.1)
				(type default)
			)
			(layer "F.Fab")
		)
		(fp_line
			(start 0.12065 -0.3048)
			(end 0.67945 -0.3048)
			(stroke
				(width 0.1)
				(type default)
			)
			(layer "F.Fab")
		)
		(fp_line
			(start 0.12065 -0.2794)
			(end 0.12065 -0.3048)
			(stroke
				(width 0.1)
				(type default)
			)
			(layer "F.Fab")
		)
		(fp_line
			(start -0.12065 -0.2794)
			(end 0.12065 -0.2794)
			(stroke
				(width 0.1)
				(type default)
			)
			(layer "F.Fab")
		)
		(fp_line
			(start 0.120396 0.2794)
			(end -0.12065 0.2794)
			(stroke
				(width 0.1)
				(type default)
			)
			(layer "F.Fab")
		)
		(fp_line
			(start -0.12065 0.2794)
			(end -0.12065 0.3048)
			(stroke
				(width 0.1)
				(type default)
			)
			(layer "F.Fab")
		)
		(fp_line
			(start 0.67945 0.3048)
			(end 0.120396 0.3048)
			(stroke
				(width 0.1)
				(type default)
			)
			(layer "F.Fab")
		)
		(fp_line
			(start 0.120396 0.3048)
			(end 0.120396 0.2794)
			(stroke
				(width 0.1)
				(type default)
			)
			(layer "F.Fab")
		)
		(fp_line
			(start -0.12065 0.3048)
			(end -0.67945 0.3048)
			(stroke
				(width 0.1)
				(type default)
			)
			(layer "F.Fab")
		)
		(fp_line
			(start -0.67945 0.3048)
			(end -0.67945 -0.305054)
			(stroke
				(width 0.1)
				(type default)
			)
			(layer "F.Fab")
		)
		(pad "1" smd circle
			(at -0.40005 0 90)
			(size 0 0)
			(layers "F.Cu" "F.Mask" "F.Paste")
			(net "PVDDIO_P0_EN")
		)
		(pad "2" smd circle
			(at 0.40005 0 90)
			(size 0 0)
			(layers "F.Cu" "F.Mask" "F.Paste")
			(net "PVDDIO_P0_EN_R")
		)
	)
	(footprint ""
		(layer "F.Cu")
		(at 71.035164 -16.315944)
		(property "Reference" "R1325"
			(at 1.889506 -2.226056 90)
			(unlocked yes)
			(layer "F.SilkS")
			(effects
				(font
					(size 0.7874 0.5842)
					(thickness 0.1524)
				)
				(justify left)
			)
		)
		(property "Value" ""
			(at 0 0 0)
			(layer "F.Fab")
			(effects
				(font
					(size 1.27 1.27)
				)
			)
		)
		(duplicate_pad_numbers_are_jumpers no)
		(fp_line
			(start -3.937508 -1.8796)
			(end -3.937508 1.8796)
			(stroke
				(width 0.1524)
				(type default)
			)
			(layer "F.SilkS")
		)
		(fp_line
			(start -3.937508 1.8796)
			(end 3.937508 1.8796)
			(stroke
				(width 0.1524)
				(type default)
			)
			(layer "F.SilkS")
		)
		(fp_line
			(start 3.937508 -1.8796)
			(end -3.937508 -1.8796)
			(stroke
				(width 0.1524)
				(type default)
			)
			(layer "F.SilkS")
		)
		(fp_line
			(start 3.937508 1.8796)
			(end 3.937508 -1.8796)
			(stroke
				(width 0.1524)
				(type default)
			)
			(layer "F.SilkS")
		)
		(fp_line
			(start -3.275076 -1.674876)
			(end -3.275076 1.674876)
			(stroke
				(width 0.1)
				(type default)
			)
			(layer "F.Fab")
		)
		(fp_line
			(start -3.275076 1.674876)
			(end 3.275076 1.674876)
			(stroke
				(width 0.1)
				(type default)
			)
			(layer "F.Fab")
		)
		(fp_line
			(start 3.275076 -1.674876)
			(end -3.275076 -1.674876)
			(stroke
				(width 0.1)
				(type default)
			)
			(layer "F.Fab")
		)
		(fp_line
			(start 3.275076 1.674876)
			(end 3.275076 -1.674876)
			(stroke
				(width 0.1)
				(type default)
			)
			(layer "F.Fab")
		)
		(pad "1" smd rect
			(at -2.350008 0)
			(size 2.921 3.5052)
			(layers "F.Cu" "F.Mask" "F.Paste")
			(net "P12V_OCP_V3_2_R")
		)
		(pad "2" smd rect
			(at 2.350008 0)
			(size 2.921 3.5052)
			(layers "F.Cu" "F.Mask" "F.Paste")
			(net "P12V_OCP_V3_2")
		)
	)
	(footprint ""
		(layer "F.Cu")
		(at 307.404516 -433.942744 90)
		(property "Reference" "R3464"
			(at 0 0 90)
			(layer "F.SilkS")
			(hide yes)
			(effects
				(font
					(size 1.27 1.27)
				)
			)
		)
		(property "Value" ""
			(at 0 0 90)
			(layer "F.Fab")
			(effects
				(font
					(size 1.27 1.27)
				)
			)
		)
		(duplicate_pad_numbers_are_jumpers no)
		(fp_line
			(start 0.7874 -0.4064)
			(end 0.7874 0.4064)
			(stroke
				(width 0.1524)
				(type default)
			)
			(layer "F.SilkS")
		)
		(fp_line
			(start -0.7874 -0.4064)
			(end 0.7874 -0.4064)
			(stroke
				(width 0.1524)
				(type default)
			)
			(layer "F.SilkS")
		)
		(fp_line
			(start 0.7874 0.4064)
			(end -0.7874 0.4064)
			(stroke
				(width 0.1524)
				(type default)
			)
			(layer "F.SilkS")
		)
		(fp_line
			(start -0.7874 0.4064)
			(end -0.7874 -0.4064)
			(stroke
				(width 0.1524)
				(type default)
			)
			(layer "F.SilkS")
		)
		(fp_line
			(start -0.12065 -0.305054)
			(end -0.12065 -0.2794)
			(stroke
				(width 0.1)
				(type default)
			)
			(layer "F.Fab")
		)
		(fp_line
			(start -0.67945 -0.305054)
			(end -0.12065 -0.305054)
			(stroke
				(width 0.1)
				(type default)
			)
			(layer "F.Fab")
		)
		(fp_line
			(start 0.67945 -0.3048)
			(end 0.67945 0.3048)
			(stroke
				(width 0.1)
				(type default)
			)
			(layer "F.Fab")
		)
		(fp_line
			(start 0.12065 -0.3048)
			(end 0.67945 -0.3048)
			(stroke
				(width 0.1)
				(type default)
			)
			(layer "F.Fab")
		)
		(fp_line
			(start 0.12065 -0.2794)
			(end 0.12065 -0.3048)
			(stroke
				(width 0.1)
				(type default)
			)
			(layer "F.Fab")
		)
		(fp_line
			(start -0.12065 -0.2794)
			(end 0.12065 -0.2794)
			(stroke
				(width 0.1)
				(type default)
			)
			(layer "F.Fab")
		)
		(fp_line
			(start 0.120396 0.2794)
			(end -0.12065 0.2794)
			(stroke
				(width 0.1)
				(type default)
			)
			(layer "F.Fab")
		)
		(fp_line
			(start -0.12065 0.2794)
			(end -0.12065 0.3048)
			(stroke
				(width 0.1)
				(type default)
			)
			(layer "F.Fab")
		)
		(fp_line
			(start 0.67945 0.3048)
			(end 0.120396 0.3048)
			(stroke
				(width 0.1)
				(type default)
			)
			(layer "F.Fab")
		)
		(fp_line
			(start 0.120396 0.3048)
			(end 0.120396 0.2794)
			(stroke
				(width 0.1)
				(type default)
			)
			(layer "F.Fab")
		)
		(fp_line
			(start -0.12065 0.3048)
			(end -0.67945 0.3048)
			(stroke
				(width 0.1)
				(type default)
			)
			(layer "F.Fab")
		)
		(fp_line
			(start -0.67945 0.3048)
			(end -0.67945 -0.305054)
			(stroke
				(width 0.1)
				(type default)
			)
			(layer "F.Fab")
		)
		(pad "1" smd circle
			(at -0.40005 0 90)
			(size 0 0)
			(layers "F.Cu" "F.Mask" "F.Paste")
			(net "P3V3_AUX")
		)
		(pad "2" smd circle
			(at 0.40005 0 90)
			(size 0 0)
			(layers "F.Cu" "F.Mask" "F.Paste")
			(net "GPU_FPGA_OVERT_N")
		)
	)
	(footprint ""
		(layer "F.Cu")
		(at 102.09657 -406.03424 180)
		(property "Reference" "R6788"
			(at 0 0 180)
			(layer "F.SilkS")
			(hide yes)
			(effects
				(font
					(size 1.27 1.27)
				)
			)
		)
		(property "Value" ""
			(at 0 0 180)
			(layer "F.Fab")
			(effects
				(font
					(size 1.27 1.27)
				)
			)
		)
		(duplicate_pad_numbers_are_jumpers no)
		(fp_line
			(start 0.32512 0.175006)
			(end -0.32512 0.175006)
			(stroke
				(width 0.1)
				(type default)
			)
			(layer "F.Fab")
		)
		(fp_line
			(start 0.32512 -0.175006)
			(end 0.32512 0.175006)
			(stroke
				(width 0.1)
				(type default)
			)
			(layer "F.Fab")
		)
		(fp_line
			(start -0.32512 0.175006)
			(end -0.32512 -0.175006)
			(stroke
				(width 0.1)
				(type default)
			)
			(layer "F.Fab")
		)
		(fp_line
			(start -0.32512 -0.175006)
			(end 0.32512 -0.175006)
			(stroke
				(width 0.1)
				(type default)
			)
			(layer "F.Fab")
		)
		(pad "1" smd rect
			(at -0.2667 0 180)
			(size 0.3048 0.381)
			(layers "F.Cu" "F.Mask" "F.Paste")
			(net "U12_E2")
		)
		(pad "2" smd rect
			(at 0.2667 0)
			(size 0.3048 0.381)
			(layers "F.Cu" "F.Mask" "F.Paste")
			(net "GND")
		)
	)
	(footprint ""
		(layer "F.Cu")
		(at 305.819048 -47.037498 180)
		(property "Reference" "R3690"
			(at 0 0 180)
			(layer "F.SilkS")
			(hide yes)
			(effects
				(font
					(size 1.27 1.27)
				)
			)
		)
		(property "Value" ""
			(at 0 0 180)
			(layer "F.Fab")
			(effects
				(font
					(size 1.27 1.27)
				)
			)
		)
		(duplicate_pad_numbers_are_jumpers no)
		(fp_line
			(start 0.7874 0.4064)
			(end -0.7874 0.4064)
			(stroke
				(width 0.1524)
				(type default)
			)
			(layer "F.SilkS")
		)
		(fp_line
			(start 0.7874 -0.4064)
			(end 0.7874 0.4064)
			(stroke
				(width 0.1524)
				(type default)
			)
			(layer "F.SilkS")
		)
		(fp_line
			(start -0.7874 0.4064)
			(end -0.7874 -0.4064)
			(stroke
				(width 0.1524)
				(type default)
			)
			(layer "F.SilkS")
		)
		(fp_line
			(start -0.7874 -0.4064)
			(end 0.7874 -0.4064)
			(stroke
				(width 0.1524)
				(type default)
			)
			(layer "F.SilkS")
		)
		(fp_line
			(start 0.67945 0.3048)
			(end 0.120396 0.3048)
			(stroke
				(width 0.1)
				(type default)
			)
			(layer "F.Fab")
		)
		(fp_line
			(start 0.67945 -0.3048)
			(end 0.67945 0.3048)
			(stroke
				(width 0.1)
				(type default)
			)
			(layer "F.Fab")
		)
		(fp_line
			(start 0.12065 -0.2794)
			(end 0.12065 -0.3048)
			(stroke
				(width 0.1)
				(type default)
			)
			(layer "F.Fab")
		)
		(fp_line
			(start 0.12065 -0.3048)
			(end 0.67945 -0.3048)
			(stroke
				(width 0.1)
				(type default)
			)
			(layer "F.Fab")
		)
		(fp_line
			(start 0.120396 0.3048)
			(end 0.120396 0.2794)
			(stroke
				(width 0.1)
				(type default)
			)
			(layer "F.Fab")
		)
		(fp_line
			(start 0.120396 0.2794)
			(end -0.12065 0.2794)
			(stroke
				(width 0.1)
				(type default)
			)
			(layer "F.Fab")
		)
		(fp_line
			(start -0.12065 0.3048)
			(end -0.67945 0.3048)
			(stroke
				(width 0.1)
				(type default)
			)
			(layer "F.Fab")
		)
		(fp_line
			(start -0.12065 0.2794)
			(end -0.12065 0.3048)
			(stroke
				(width 0.1)
				(type default)
			)
			(layer "F.Fab")
		)
		(fp_line
			(start -0.12065 -0.2794)
			(end 0.12065 -0.2794)
			(stroke
				(width 0.1)
				(type default)
			)
			(layer "F.Fab")
		)
		(fp_line
			(start -0.12065 -0.305054)
			(end -0.12065 -0.2794)
			(stroke
				(width 0.1)
				(type default)
			)
			(layer "F.Fab")
		)
		(fp_line
			(start -0.67945 0.3048)
			(end -0.67945 -0.305054)
			(stroke
				(width 0.1)
				(type default)
			)
			(layer "F.Fab")
		)
		(fp_line
			(start -0.67945 -0.305054)
			(end -0.12065 -0.305054)
			(stroke
				(width 0.1)
				(type default)
			)
			(layer "F.Fab")
		)
		(pad "1" smd circle
			(at -0.40005 0 180)
			(size 0 0)
			(layers "F.Cu" "F.Mask" "F.Paste")
			(net "ADC128_VREF")
		)
		(pad "2" smd circle
			(at 0.40005 0 180)
			(size 0 0)
			(layers "F.Cu" "F.Mask" "F.Paste")
			(net "GND")
		)
	)
)
